(kicad_pcb
	(version 20260206)
	(generator "pcbnew")
	(generator_version "10.0")
	(general
		(thickness 1.6)
		(legacy_teardrops no)
	)
	(paper "A4")
	(title_block
		(title "01162023_DA0F0TEBIF0_F0T_Expander_BD_F_brd_V02_OCP.brd")
		(comment 1 "Grand Teton / footprints 281-287 of 9728")
	)
	(layers
		(0 "F.Cu" signal "TOP")
		(4 "In1.Cu" signal "GND")
		(6 "In2.Cu" signal "VCC")
		(8 "In3.Cu" signal "VCC1")
		(10 "In4.Cu" signal "GND1")
		(12 "In5.Cu" signal "IN1")
		(14 "In6.Cu" signal "GND2")
		(16 "In7.Cu" signal "IN2")
		(18 "In8.Cu" signal "GND3")
		(20 "In9.Cu" signal "IN3")
		(22 "In10.Cu" signal "GND4")
		(24 "In11.Cu" signal "IN4")
		(26 "In12.Cu" signal "GND5")
		(28 "In13.Cu" signal "IN5")
		(30 "In14.Cu" signal "GND6")
		(32 "In15.Cu" signal "IN6")
		(34 "In16.Cu" signal "GND7")
		(2 "B.Cu" signal "BOTTOM")
		(9 "F.Adhes" user "F.Adhesive")
		(11 "B.Adhes" user "B.Adhesive")
		(13 "F.Paste" user "Package Geometry/Pastemask Top")
		(15 "B.Paste" user "Package Geometry/Pastemask Bottom")
		(5 "F.SilkS" user "Ref Des/Silkscreen Top")
		(7 "B.SilkS" user "Ref Des/Silkscreen Bottom")
		(1 "F.Mask" user "Board Geometry/Soldermask Top")
		(3 "B.Mask" user "Board Geometry/Soldermask Bottom")
		(17 "Dwgs.User" user "User.Drawings")
		(19 "Cmts.User" user "User.Comments")
		(21 "Eco1.User" user "User.Eco1")
		(23 "Eco2.User" user "User.Eco2")
		(25 "Edge.Cuts" user "Board Geometry/Outline")
		(27 "Margin" user)
		(31 "F.CrtYd" user "Package Geometry/Place Bound Top")
		(29 "B.CrtYd" user "Package Geometry/Place Bound Bottom")
		(35 "F.Fab" user "Ref Des/Assembly Top")
		(33 "B.Fab" user "Ref Des/Assembly Bottom")
	)
	(footprint ""
		(layer "F.Cu")
		(at 91.624658 -115.835176 90)
		(property "Reference" "PU79"
			(at 1.70434 -3.349244 0)
			(unlocked yes)
			(layer "F.SilkS")
			(effects
				(font
					(size 0.7874 0.5842)
					(thickness 0.1524)
				)
			)
		)
		(property "Value" ""
			(at 0 0 90)
			(layer "F.Fab")
			(effects
				(font
					(size 1.27 1.27)
				)
			)
		)
		(duplicate_pad_numbers_are_jumpers no)
		(fp_line
			(start 1.239774 -1.495298)
			(end 1.239774 1.495298)
			(stroke
				(width 0.1524)
				(type default)
			)
			(layer "F.SilkS")
		)
		(fp_line
			(start -1.239774 -1.495298)
			(end 1.239774 -1.495298)
			(stroke
				(width 0.1524)
				(type default)
			)
			(layer "F.SilkS")
		)
		(fp_line
			(start 1.239774 1.495298)
			(end -1.239774 1.495298)
			(stroke
				(width 0.1524)
				(type default)
			)
			(layer "F.SilkS")
		)
		(fp_line
			(start -1.239774 1.495298)
			(end -1.239774 -1.495298)
			(stroke
				(width 0.1524)
				(type default)
			)
			(layer "F.SilkS")
		)
		(fp_poly
			(pts
				(xy -1.790954 -1.360932) (xy -2.50952 -0.64262) (xy -1.431798 -0.283464)
			)
			(stroke
				(width 0)
				(type default)
			)
			(fill yes)
			(layer "F.SilkS")
		)
		(fp_line
			(start 0.8001 -1.050036)
			(end 0.8001 1.050036)
			(stroke
				(width 0.1)
				(type default)
			)
			(layer "F.Fab")
		)
		(fp_line
			(start -0.8001 -1.050036)
			(end 0.8001 -1.050036)
			(stroke
				(width 0.1)
				(type default)
			)
			(layer "F.Fab")
		)
		(fp_line
			(start 0.8001 1.050036)
			(end -0.8001 1.050036)
			(stroke
				(width 0.1)
				(type default)
			)
			(layer "F.Fab")
		)
		(fp_line
			(start -0.8001 1.050036)
			(end -0.8001 -1.050036)
			(stroke
				(width 0.1)
				(type default)
			)
			(layer "F.Fab")
		)
		(fp_poly
			(pts
				(xy -2.458974 -0.508) (xy -2.458974 0.508) (xy -1.442974 0)
			)
			(stroke
				(width 0)
				(type default)
			)
			(fill yes)
			(layer "F.Fab")
		)
		(pad "1_2" smd circle
			(at -0.374904 0 180)
			(size 0 0)
			(layers "F.Cu" "F.Mask" "F.Paste")
			(net "P3V3_AUX")
		)
		(pad "3" smd rect
			(at -0.499872 0.999998 90)
			(size 0.254 0.7112)
			(layers "F.Cu" "F.Mask" "F.Paste")
			(net "GND")
		)
		(pad "4" smd rect
			(at 0 0.999998 90)
			(size 0.254 0.7112)
			(layers "F.Cu" "F.Mask" "F.Paste")
			(net "P3V3_NIC1_CO_ILIMIT")
		)
		(pad "5" smd rect
			(at 0.499872 0.999998 90)
			(size 0.254 0.7112)
			(layers "F.Cu" "F.Mask" "F.Paste")
			(net "P3V3_NIC1_CO_MODE")
		)
		(pad "6_7" smd circle
			(at 0.374904 0)
			(size 0 0)
			(layers "F.Cu" "F.Mask" "F.Paste")
			(net "P3V3_NIC1")
		)
		(pad "8" smd rect
			(at 0.499872 -0.999998 90)
			(size 0.254 0.7112)
			(layers "F.Cu" "F.Mask" "F.Paste")
			(net "P3V3_NIC1_CO_GATE")
		)
		(pad "9" smd rect
			(at 0 -0.999998 90)
			(size 0.254 0.7112)
			(layers "F.Cu" "F.Mask" "F.Paste")
			(net "P3V3_NIC1_CO_EN")
		)
		(pad "10" smd rect
			(at -0.499872 -0.999998 90)
			(size 0.254 0.7112)
			(layers "F.Cu" "F.Mask" "F.Paste")
			(net "P3V3_NIC1_CO_DV_DT")
		)
	)
	(footprint ""
		(layer "F.Cu")
		(at 380.717044 -308.852062 -135)
		(property "Reference" "R1462"
			(at 0 0 225)
			(layer "F.SilkS")
			(hide yes)
			(effects
				(font
					(size 1.27 1.27)
				)
			)
		)
		(property "Value" ""
			(at 0 0 225)
			(layer "F.Fab")
			(effects
				(font
					(size 1.27 1.27)
				)
			)
		)
		(duplicate_pad_numbers_are_jumpers no)
		(fp_line
			(start 0.787389 0.406267)
			(end -0.787389 0.406267)
			(stroke
				(width 0.1524)
				(type default)
			)
			(layer "F.SilkS")
		)
		(fp_line
			(start 0.787389 -0.406267)
			(end 0.787389 0.406267)
			(stroke
				(width 0.1524)
				(type default)
			)
			(layer "F.SilkS")
		)
		(fp_line
			(start -0.787389 0.406267)
			(end -0.787389 -0.406267)
			(stroke
				(width 0.1524)
				(type default)
			)
			(layer "F.SilkS")
		)
		(fp_line
			(start -0.787389 -0.406267)
			(end 0.787389 -0.406267)
			(stroke
				(width 0.1524)
				(type default)
			)
			(layer "F.SilkS")
		)
		(fp_line
			(start 0.679446 0.30479)
			(end 0.120515 0.30479)
			(stroke
				(width 0.1)
				(type default)
			)
			(layer "F.Fab")
		)
		(fp_line
			(start 0.120515 0.30479)
			(end 0.120335 0.279466)
			(stroke
				(width 0.1)
				(type default)
			)
			(layer "F.Fab")
		)
		(fp_line
			(start 0.120335 0.279466)
			(end -0.120695 0.279466)
			(stroke
				(width 0.1)
				(type default)
			)
			(layer "F.Fab")
		)
		(fp_line
			(start 0.679446 -0.30479)
			(end 0.679446 0.30479)
			(stroke
				(width 0.1)
				(type default)
			)
			(layer "F.Fab")
		)
		(fp_line
			(start -0.120515 0.30479)
			(end -0.679446 0.30479)
			(stroke
				(width 0.1)
				(type default)
			)
			(layer "F.Fab")
		)
		(fp_line
			(start -0.120695 0.279466)
			(end -0.120515 0.30479)
			(stroke
				(width 0.1)
				(type default)
			)
			(layer "F.Fab")
		)
		(fp_line
			(start 0.120695 -0.279466)
			(end 0.120515 -0.30479)
			(stroke
				(width 0.1)
				(type default)
			)
			(layer "F.Fab")
		)
		(fp_line
			(start 0.120515 -0.30479)
			(end 0.679446 -0.30479)
			(stroke
				(width 0.1)
				(type default)
			)
			(layer "F.Fab")
		)
		(fp_line
			(start -0.679446 0.30479)
			(end -0.679446 -0.305149)
			(stroke
				(width 0.1)
				(type default)
			)
			(layer "F.Fab")
		)
		(fp_line
			(start -0.120695 -0.279466)
			(end 0.120695 -0.279466)
			(stroke
				(width 0.1)
				(type default)
			)
			(layer "F.Fab")
		)
		(fp_line
			(start -0.120695 -0.304969)
			(end -0.120695 -0.279466)
			(stroke
				(width 0.1)
				(type default)
			)
			(layer "F.Fab")
		)
		(fp_line
			(start -0.679446 -0.305149)
			(end -0.120695 -0.304969)
			(stroke
				(width 0.1)
				(type default)
			)
			(layer "F.Fab")
		)
		(pad "1" smd circle
			(at -0.40005 0 225)
			(size 0 0)
			(layers "F.Cu" "F.Mask" "F.Paste")
			(net "PU_PEX3_ATPG_MODE_L")
		)
		(pad "2" smd circle
			(at 0.40005 0 225)
			(size 0 0)
			(layers "F.Cu" "F.Mask" "F.Paste")
			(net "P1V8_PEX")
		)
	)
	(footprint ""
		(layer "F.Cu")
		(at 73.289922 -72.766682 90)
		(property "Reference" "PR6910"
			(at 0 0 90)
			(layer "F.SilkS")
			(hide yes)
			(effects
				(font
					(size 1.27 1.27)
				)
			)
		)
		(property "Value" ""
			(at 0 0 90)
			(layer "F.Fab")
			(effects
				(font
					(size 1.27 1.27)
				)
			)
		)
		(duplicate_pad_numbers_are_jumpers no)
		(fp_line
			(start 0.7874 -0.4064)
			(end 0.7874 0.4064)
			(stroke
				(width 0.1524)
				(type default)
			)
			(layer "F.SilkS")
		)
		(fp_line
			(start -0.7874 -0.4064)
			(end 0.7874 -0.4064)
			(stroke
				(width 0.1524)
				(type default)
			)
			(layer "F.SilkS")
		)
		(fp_line
			(start 0.7874 0.4064)
			(end -0.7874 0.4064)
			(stroke
				(width 0.1524)
				(type default)
			)
			(layer "F.SilkS")
		)
		(fp_line
			(start -0.7874 0.4064)
			(end -0.7874 -0.4064)
			(stroke
				(width 0.1524)
				(type default)
			)
			(layer "F.SilkS")
		)
		(fp_line
			(start -0.12065 -0.305054)
			(end -0.12065 -0.2794)
			(stroke
				(width 0.1)
				(type default)
			)
			(layer "F.Fab")
		)
		(fp_line
			(start -0.67945 -0.305054)
			(end -0.12065 -0.305054)
			(stroke
				(width 0.1)
				(type default)
			)
			(layer "F.Fab")
		)
		(fp_line
			(start 0.67945 -0.3048)
			(end 0.67945 0.3048)
			(stroke
				(width 0.1)
				(type default)
			)
			(layer "F.Fab")
		)
		(fp_line
			(start 0.12065 -0.3048)
			(end 0.67945 -0.3048)
			(stroke
				(width 0.1)
				(type default)
			)
			(layer "F.Fab")
		)
		(fp_line
			(start 0.12065 -0.2794)
			(end 0.12065 -0.3048)
			(stroke
				(width 0.1)
				(type default)
			)
			(layer "F.Fab")
		)
		(fp_line
			(start -0.12065 -0.2794)
			(end 0.12065 -0.2794)
			(stroke
				(width 0.1)
				(type default)
			)
			(layer "F.Fab")
		)
		(fp_line
			(start 0.120396 0.2794)
			(end -0.12065 0.2794)
			(stroke
				(width 0.1)
				(type default)
			)
			(layer "F.Fab")
		)
		(fp_line
			(start -0.12065 0.2794)
			(end -0.12065 0.3048)
			(stroke
				(width 0.1)
				(type default)
			)
			(layer "F.Fab")
		)
		(fp_line
			(start 0.67945 0.3048)
			(end 0.120396 0.3048)
			(stroke
				(width 0.1)
				(type default)
			)
			(layer "F.Fab")
		)
		(fp_line
			(start 0.120396 0.3048)
			(end 0.120396 0.2794)
			(stroke
				(width 0.1)
				(type default)
			)
			(layer "F.Fab")
		)
		(fp_line
			(start -0.12065 0.3048)
			(end -0.67945 0.3048)
			(stroke
				(width 0.1)
				(type default)
			)
			(layer "F.Fab")
		)
		(fp_line
			(start -0.67945 0.3048)
			(end -0.67945 -0.305054)
			(stroke
				(width 0.1)
				(type default)
			)
			(layer "F.Fab")
		)
		(pad "1" smd circle
			(at -0.40005 0 90)
			(size 0 0)
			(layers "F.Cu" "F.Mask" "F.Paste")
			(net "P12V_SSD2_CO_ILIMIT")
		)
		(pad "2" smd circle
			(at 0.40005 0 90)
			(size 0 0)
			(layers "F.Cu" "F.Mask" "F.Paste")
			(net "GND")
		)
	)
	(footprint ""
		(layer "F.Cu")
		(at 214.310976 -367.019586 180)
		(property "Reference" "PR34"
			(at 0 0 180)
			(layer "F.SilkS")
			(hide yes)
			(effects
				(font
					(size 1.27 1.27)
				)
			)
		)
		(property "Value" ""
			(at 0 0 180)
			(layer "F.Fab")
			(effects
				(font
					(size 1.27 1.27)
				)
			)
		)
		(duplicate_pad_numbers_are_jumpers no)
		(fp_line
			(start 0.7874 0.4064)
			(end -0.7874 0.4064)
			(stroke
				(width 0.1524)
				(type default)
			)
			(layer "F.SilkS")
		)
		(fp_line
			(start 0.7874 -0.4064)
			(end 0.7874 0.4064)
			(stroke
				(width 0.1524)
				(type default)
			)
			(layer "F.SilkS")
		)
		(fp_line
			(start -0.7874 0.4064)
			(end -0.7874 -0.4064)
			(stroke
				(width 0.1524)
				(type default)
			)
			(layer "F.SilkS")
		)
		(fp_line
			(start -0.7874 -0.4064)
			(end 0.7874 -0.4064)
			(stroke
				(width 0.1524)
				(type default)
			)
			(layer "F.SilkS")
		)
		(fp_line
			(start 0.67945 0.3048)
			(end 0.120396 0.3048)
			(stroke
				(width 0.1)
				(type default)
			)
			(layer "F.Fab")
		)
		(fp_line
			(start 0.67945 -0.3048)
			(end 0.67945 0.3048)
			(stroke
				(width 0.1)
				(type default)
			)
			(layer "F.Fab")
		)
		(fp_line
			(start 0.12065 -0.2794)
			(end 0.12065 -0.3048)
			(stroke
				(width 0.1)
				(type default)
			)
			(layer "F.Fab")
		)
		(fp_line
			(start 0.12065 -0.3048)
			(end 0.67945 -0.3048)
			(stroke
				(width 0.1)
				(type default)
			)
			(layer "F.Fab")
		)
		(fp_line
			(start 0.120396 0.3048)
			(end 0.120396 0.2794)
			(stroke
				(width 0.1)
				(type default)
			)
			(layer "F.Fab")
		)
		(fp_line
			(start 0.120396 0.2794)
			(end -0.12065 0.2794)
			(stroke
				(width 0.1)
				(type default)
			)
			(layer "F.Fab")
		)
		(fp_line
			(start -0.12065 0.3048)
			(end -0.67945 0.3048)
			(stroke
				(width 0.1)
				(type default)
			)
			(layer "F.Fab")
		)
		(fp_line
			(start -0.12065 0.2794)
			(end -0.12065 0.3048)
			(stroke
				(width 0.1)
				(type default)
			)
			(layer "F.Fab")
		)
		(fp_line
			(start -0.12065 -0.2794)
			(end 0.12065 -0.2794)
			(stroke
				(width 0.1)
				(type default)
			)
			(layer "F.Fab")
		)
		(fp_line
			(start -0.12065 -0.305054)
			(end -0.12065 -0.2794)
			(stroke
				(width 0.1)
				(type default)
			)
			(layer "F.Fab")
		)
		(fp_line
			(start -0.67945 0.3048)
			(end -0.67945 -0.305054)
			(stroke
				(width 0.1)
				(type default)
			)
			(layer "F.Fab")
		)
		(fp_line
			(start -0.67945 -0.305054)
			(end -0.12065 -0.305054)
			(stroke
				(width 0.1)
				(type default)
			)
			(layer "F.Fab")
		)
		(pad "1" smd circle
			(at -0.40005 0 180)
			(size 0 0)
			(layers "F.Cu" "F.Mask" "F.Paste")
			(net "HSC_CS_1")
		)
		(pad "2" smd circle
			(at 0.40005 0 180)
			(size 0 0)
			(layers "F.Cu" "F.Mask" "F.Paste")
			(net "AGND_HSC")
		)
	)
	(footprint ""
		(layer "F.Cu")
		(at 155.380436 -133.129782)
		(property "Reference" "C249"
			(at 0 0 0)
			(layer "F.SilkS")
			(hide yes)
			(effects
				(font
					(size 1.27 1.27)
				)
			)
		)
		(property "Value" ""
			(at 0 0 0)
			(layer "F.Fab")
			(effects
				(font
					(size 1.27 1.27)
				)
			)
		)
		(duplicate_pad_numbers_are_jumpers no)
		(fp_line
			(start -0.299974 -0.150114)
			(end 0.299974 -0.150114)
			(stroke
				(width 0.1)
				(type default)
			)
			(layer "F.Fab")
		)
		(fp_line
			(start -0.299974 0.150114)
			(end -0.299974 -0.150114)
			(stroke
				(width 0.1)
				(type default)
			)
			(layer "F.Fab")
		)
		(fp_line
			(start 0.299974 -0.150114)
			(end 0.299974 0.150114)
			(stroke
				(width 0.1)
				(type default)
			)
			(layer "F.Fab")
		)
		(fp_line
			(start 0.299974 0.150114)
			(end -0.299974 0.150114)
			(stroke
				(width 0.1)
				(type default)
			)
			(layer "F.Fab")
		)
		(pad "1" smd rect
			(at -0.2667 0)
			(size 0.3048 0.381)
			(layers "F.Cu" "F.Mask" "F.Paste")
			(net "P5E_PEX1_STN1_TX_DP<29>")
		)
		(pad "2" smd rect
			(at 0.2667 0)
			(size 0.3048 0.381)
			(layers "F.Cu" "F.Mask" "F.Paste")
			(net "P5E_PEX1_STN1_TX_C_DP<29>")
		)
	)
	(footprint ""
		(layer "F.Cu")
		(at 284.226 -83.566 180)
		(property "Reference" "R486"
			(at 0 0 180)
			(layer "F.SilkS")
			(hide yes)
			(effects
				(font
					(size 1.27 1.27)
				)
			)
		)
		(property "Value" ""
			(at 0 0 180)
			(layer "F.Fab")
			(effects
				(font
					(size 1.27 1.27)
				)
			)
		)
		(duplicate_pad_numbers_are_jumpers no)
		(fp_line
			(start 0.7874 0.4064)
			(end -0.7874 0.4064)
			(stroke
				(width 0.1524)
				(type default)
			)
			(layer "F.SilkS")
		)
		(fp_line
			(start 0.7874 -0.4064)
			(end 0.7874 0.4064)
			(stroke
				(width 0.1524)
				(type default)
			)
			(layer "F.SilkS")
		)
		(fp_line
			(start -0.7874 0.4064)
			(end -0.7874 -0.4064)
			(stroke
				(width 0.1524)
				(type default)
			)
			(layer "F.SilkS")
		)
		(fp_line
			(start -0.7874 -0.4064)
			(end 0.7874 -0.4064)
			(stroke
				(width 0.1524)
				(type default)
			)
			(layer "F.SilkS")
		)
		(fp_line
			(start 0.67945 0.3048)
			(end 0.120396 0.3048)
			(stroke
				(width 0.1)
				(type default)
			)
			(layer "F.Fab")
		)
		(fp_line
			(start 0.67945 -0.3048)
			(end 0.67945 0.3048)
			(stroke
				(width 0.1)
				(type default)
			)
			(layer "F.Fab")
		)
		(fp_line
			(start 0.12065 -0.2794)
			(end 0.12065 -0.3048)
			(stroke
				(width 0.1)
				(type default)
			)
			(layer "F.Fab")
		)
		(fp_line
			(start 0.12065 -0.3048)
			(end 0.67945 -0.3048)
			(stroke
				(width 0.1)
				(type default)
			)
			(layer "F.Fab")
		)
		(fp_line
			(start 0.120396 0.3048)
			(end 0.120396 0.2794)
			(stroke
				(width 0.1)
				(type default)
			)
			(layer "F.Fab")
		)
		(fp_line
			(start 0.120396 0.2794)
			(end -0.12065 0.2794)
			(stroke
				(width 0.1)
				(type default)
			)
			(layer "F.Fab")
		)
		(fp_line
			(start -0.12065 0.3048)
			(end -0.67945 0.3048)
			(stroke
				(width 0.1)
				(type default)
			)
			(layer "F.Fab")
		)
		(fp_line
			(start -0.12065 0.2794)
			(end -0.12065 0.3048)
			(stroke
				(width 0.1)
				(type default)
			)
			(layer "F.Fab")
		)
		(fp_line
			(start -0.12065 -0.2794)
			(end 0.12065 -0.2794)
			(stroke
				(width 0.1)
				(type default)
			)
			(layer "F.Fab")
		)
		(fp_line
			(start -0.12065 -0.305054)
			(end -0.12065 -0.2794)
			(stroke
				(width 0.1)
				(type default)
			)
			(layer "F.Fab")
		)
		(fp_line
			(start -0.67945 0.3048)
			(end -0.67945 -0.305054)
			(stroke
				(width 0.1)
				(type default)
			)
			(layer "F.Fab")
		)
		(fp_line
			(start -0.67945 -0.305054)
			(end -0.12065 -0.305054)
			(stroke
				(width 0.1)
				(type default)
			)
			(layer "F.Fab")
		)
		(pad "1" smd circle
			(at -0.40005 0 180)
			(size 0 0)
			(layers "F.Cu" "F.Mask" "F.Paste")
			(net "BB_FRU_A2")
		)
		(pad "2" smd circle
			(at 0.40005 0 180)
			(size 0 0)
			(layers "F.Cu" "F.Mask" "F.Paste")
			(net "P3V3_AUX")
		)
	)
	(footprint ""
		(layer "F.Cu")
		(at 411.108652 -158.080202 90)
		(property "Reference" "R2477"
			(at 0 0 90)
			(layer "F.SilkS")
			(hide yes)
			(effects
				(font
					(size 1.27 1.27)
				)
			)
		)
		(property "Value" ""
			(at 0 0 90)
			(layer "F.Fab")
			(effects
				(font
					(size 1.27 1.27)
				)
			)
		)
		(duplicate_pad_numbers_are_jumpers no)
		(fp_line
			(start 0.7874 -0.4064)
			(end 0.7874 0.4064)
			(stroke
				(width 0.1524)
				(type default)
			)
			(layer "F.SilkS")
		)
		(fp_line
			(start -0.7874 -0.4064)
			(end 0.7874 -0.4064)
			(stroke
				(width 0.1524)
				(type default)
			)
			(layer "F.SilkS")
		)
		(fp_line
			(start 0.7874 0.4064)
			(end -0.7874 0.4064)
			(stroke
				(width 0.1524)
				(type default)
			)
			(layer "F.SilkS")
		)
		(fp_line
			(start -0.7874 0.4064)
			(end -0.7874 -0.4064)
			(stroke
				(width 0.1524)
				(type default)
			)
			(layer "F.SilkS")
		)
		(fp_line
			(start -0.12065 -0.305054)
			(end -0.12065 -0.2794)
			(stroke
				(width 0.1)
				(type default)
			)
			(layer "F.Fab")
		)
		(fp_line
			(start -0.67945 -0.305054)
			(end -0.12065 -0.305054)
			(stroke
				(width 0.1)
				(type default)
			)
			(layer "F.Fab")
		)
		(fp_line
			(start 0.67945 -0.3048)
			(end 0.67945 0.3048)
			(stroke
				(width 0.1)
				(type default)
			)
			(layer "F.Fab")
		)
		(fp_line
			(start 0.12065 -0.3048)
			(end 0.67945 -0.3048)
			(stroke
				(width 0.1)
				(type default)
			)
			(layer "F.Fab")
		)
		(fp_line
			(start 0.12065 -0.2794)
			(end 0.12065 -0.3048)
			(stroke
				(width 0.1)
				(type default)
			)
			(layer "F.Fab")
		)
		(fp_line
			(start -0.12065 -0.2794)
			(end 0.12065 -0.2794)
			(stroke
				(width 0.1)
				(type default)
			)
			(layer "F.Fab")
		)
		(fp_line
			(start 0.120396 0.2794)
			(end -0.12065 0.2794)
			(stroke
				(width 0.1)
				(type default)
			)
			(layer "F.Fab")
		)
		(fp_line
			(start -0.12065 0.2794)
			(end -0.12065 0.3048)
			(stroke
				(width 0.1)
				(type default)
			)
			(layer "F.Fab")
		)
		(fp_line
			(start 0.67945 0.3048)
			(end 0.120396 0.3048)
			(stroke
				(width 0.1)
				(type default)
			)
			(layer "F.Fab")
		)
		(fp_line
			(start 0.120396 0.3048)
			(end 0.120396 0.2794)
			(stroke
				(width 0.1)
				(type default)
			)
			(layer "F.Fab")
		)
		(fp_line
			(start -0.12065 0.3048)
			(end -0.67945 0.3048)
			(stroke
				(width 0.1)
				(type default)
			)
			(layer "F.Fab")
		)
		(fp_line
			(start -0.67945 0.3048)
			(end -0.67945 -0.305054)
			(stroke
				(width 0.1)
				(type default)
			)
			(layer "F.Fab")
		)
		(pad "1" smd circle
			(at -0.40005 0 90)
			(size 0 0)
			(layers "F.Cu" "F.Mask" "F.Paste")
			(net "P3V3_NIC7")
		)
		(pad "2" smd circle
			(at 0.40005 0 90)
			(size 0 0)
			(layers "F.Cu" "F.Mask" "F.Paste")
			(net "NIC7_PWRBRK_N")
		)
	)
)
